# S9S_MB_2U (Grand Teton) — schematic netlist excerpt (pin names and nets, part order shuffled) for the footprints in the layout excerpt that follows; sources: Cadence DE-HDL packaged netlist, KiCad conversion of 03242023_DA0F0TMBIJ0_F0T_Motherboard_J_brd_V01_OCP.brd

PC1289  Q_CAP  1UF 16V 10% X6S  pkg C0402  page 296 : A = PVCCD_HV_CPU1_VREF ; B = GND
R3709  Q_RES  1K 1% CHIP  pkg 0402LF  page 233 : A = PCA9548_PCIE0_ADDR0 ; B = GND

(kicad_pcb
	(version 20260206)
	(generator "pcbnew")
	(generator_version "10.0")
	(general
		(thickness 1.6)
		(legacy_teardrops no)
	)
	(paper "A4")
	(title_block
		(title "03242023_DA0F0TMBIJ0_F0T_Motherboard_J_brd_V01_OCP.brd")
		(comment 1 "Grand Teton / footprints 734-735 of 6105")
	)
	(layers
		(0 "F.Cu" signal "TOP")
		(4 "In1.Cu" signal "GND")
		(6 "In2.Cu" signal "IN1")
		(8 "In3.Cu" signal "GND1")
		(10 "In4.Cu" signal "IN2")
		(12 "In5.Cu" signal "GND2")
		(14 "In6.Cu" signal "IN3")
		(16 "In7.Cu" signal "GND3")
		(18 "In8.Cu" signal "VCC")
		(20 "In9.Cu" signal "VCC1")
		(22 "In10.Cu" signal "GND4")
		(24 "In11.Cu" signal "IN4")
		(26 "In12.Cu" signal "GND5")
		(28 "In13.Cu" signal "IN5")
		(30 "In14.Cu" signal "GND6")
		(32 "In15.Cu" signal "IN6")
		(34 "In16.Cu" signal "GND7")
		(2 "B.Cu" signal "BOTTOM")
		(9 "F.Adhes" user "F.Adhesive")
		(11 "B.Adhes" user "B.Adhesive")
		(13 "F.Paste" user "Package Geometry/Pastemask Top")
		(15 "B.Paste" user "Package Geometry/Pastemask Bottom")
		(5 "F.SilkS" user "Ref Des/Silkscreen Top")
		(7 "B.SilkS" user "Ref Des/Silkscreen Bottom")
		(1 "F.Mask" user "Board Geometry/Soldermask Top")
		(3 "B.Mask" user "Board Geometry/Soldermask Bottom")
		(17 "Dwgs.User" user "User.Drawings")
		(19 "Cmts.User" user "User.Comments")
		(21 "Eco1.User" user "User.Eco1")
		(23 "Eco2.User" user "User.Eco2")
		(25 "Edge.Cuts" user "Board Geometry/Outline")
		(27 "Margin" user)
		(31 "F.CrtYd" user "Package Geometry/Place Bound Top")
		(29 "B.CrtYd" user "Package Geometry/Place Bound Bottom")
		(35 "F.Fab" user "Ref Des/Assembly Top")
		(33 "B.Fab" user "Ref Des/Assembly Bottom")
	)
	(footprint ""
		(layer "F.Cu")
		(at 28.961334 -169.000678 90)
		(property "Reference" "PC1289"
			(at 0 0 90)
			(layer "F.SilkS")
			(hide yes)
			(effects
				(font
					(size 1.27 1.27)
				)
			)
		)
		(property "Value" ""
			(at 0 0 90)
			(layer "F.Fab")
			(effects
				(font
					(size 1.27 1.27)
				)
			)
		)
		(duplicate_pad_numbers_are_jumpers no)
		(fp_line
			(start 0.7874 -0.4064)
			(end 0.7874 0.4064)
			(stroke
				(width 0.1524)
				(type default)
			)
			(layer "F.SilkS")
		)
		(fp_line
			(start -0.7874 -0.4064)
			(end 0.7874 -0.4064)
			(stroke
				(width 0.1524)
				(type default)
			)
			(layer "F.SilkS")
		)
		(fp_line
			(start 0.7874 0.4064)
			(end -0.7874 0.4064)
			(stroke
				(width 0.1524)
				(type default)
			)
			(layer "F.SilkS")
		)
		(fp_line
			(start -0.7874 0.4064)
			(end -0.7874 -0.4064)
			(stroke
				(width 0.1524)
				(type default)
			)
			(layer "F.SilkS")
		)
		(fp_line
			(start -0.12065 -0.305054)
			(end -0.12065 -0.2794)
			(stroke
				(width 0.1)
				(type default)
			)
			(layer "F.Fab")
		)
		(fp_line
			(start -0.67945 -0.305054)
			(end -0.12065 -0.305054)
			(stroke
				(width 0.1)
				(type default)
			)
			(layer "F.Fab")
		)
		(fp_line
			(start 0.67945 -0.3048)
			(end 0.67945 0.3048)
			(stroke
				(width 0.1)
				(type default)
			)
			(layer "F.Fab")
		)
		(fp_line
			(start 0.12065 -0.3048)
			(end 0.67945 -0.3048)
			(stroke
				(width 0.1)
				(type default)
			)
			(layer "F.Fab")
		)
		(fp_line
			(start 0.12065 -0.2794)
			(end 0.12065 -0.3048)
			(stroke
				(width 0.1)
				(type default)
			)
			(layer "F.Fab")
		)
		(fp_line
			(start -0.12065 -0.2794)
			(end 0.12065 -0.2794)
			(stroke
				(width 0.1)
				(type default)
			)
			(layer "F.Fab")
		)
		(fp_line
			(start 0.120396 0.2794)
			(end -0.12065 0.2794)
			(stroke
				(width 0.1)
				(type default)
			)
			(layer "F.Fab")
		)
		(fp_line
			(start -0.12065 0.2794)
			(end -0.12065 0.3048)
			(stroke
				(width 0.1)
				(type default)
			)
			(layer "F.Fab")
		)
		(fp_line
			(start 0.67945 0.3048)
			(end 0.120396 0.3048)
			(stroke
				(width 0.1)
				(type default)
			)
			(layer "F.Fab")
		)
		(fp_line
			(start 0.120396 0.3048)
			(end 0.120396 0.2794)
			(stroke
				(width 0.1)
				(type default)
			)
			(layer "F.Fab")
		)
		(fp_line
			(start -0.12065 0.3048)
			(end -0.67945 0.3048)
			(stroke
				(width 0.1)
				(type default)
			)
			(layer "F.Fab")
		)
		(fp_line
			(start -0.67945 0.3048)
			(end -0.67945 -0.305054)
			(stroke
				(width 0.1)
				(type default)
			)
			(layer "F.Fab")
		)
		(pad "1" smd circle
			(at -0.40005 0 90)
			(size 0 0)
			(layers "F.Cu" "F.Mask" "F.Paste")
			(net "PVCCD_HV_CPU1_VREF")
		)
		(pad "2" smd circle
			(at 0.40005 0 90)
			(size 0 0)
			(layers "F.Cu" "F.Mask" "F.Paste")
			(net "GND")
		)
	)
	(footprint ""
		(layer "F.Cu")
		(at 54.242716 -117.40769 180)
		(property "Reference" "R3709"
			(at 0 0 180)
			(layer "F.SilkS")
			(hide yes)
			(effects
				(font
					(size 1.27 1.27)
				)
			)
		)
		(property "Value" ""
			(at 0 0 180)
			(layer "F.Fab")
			(effects
				(font
					(size 1.27 1.27)
				)
			)
		)
		(duplicate_pad_numbers_are_jumpers no)
		(fp_line
			(start 0.7874 0.4064)
			(end -0.7874 0.4064)
			(stroke
				(width 0.1524)
				(type default)
			)
			(layer "F.SilkS")
		)
		(fp_line
			(start 0.7874 -0.4064)
			(end 0.7874 0.4064)
			(stroke
				(width 0.1524)
				(type default)
			)
			(layer "F.SilkS")
		)
		(fp_line
			(start -0.7874 0.4064)
			(end -0.7874 -0.4064)
			(stroke
				(width 0.1524)
				(type default)
			)
			(layer "F.SilkS")
		)
		(fp_line
			(start -0.7874 -0.4064)
			(end 0.7874 -0.4064)
			(stroke
				(width 0.1524)
				(type default)
			)
			(layer "F.SilkS")
		)
		(fp_line
			(start 0.67945 0.3048)
			(end 0.120396 0.3048)
			(stroke
				(width 0.1)
				(type default)
			)
			(layer "F.Fab")
		)
		(fp_line
			(start 0.67945 -0.3048)
			(end 0.67945 0.3048)
			(stroke
				(width 0.1)
				(type default)
			)
			(layer "F.Fab")
		)
		(fp_line
			(start 0.12065 -0.2794)
			(end 0.12065 -0.3048)
			(stroke
				(width 0.1)
				(type default)
			)
			(layer "F.Fab")
		)
		(fp_line
			(start 0.12065 -0.3048)
			(end 0.67945 -0.3048)
			(stroke
				(width 0.1)
				(type default)
			)
			(layer "F.Fab")
		)
		(fp_line
			(start 0.120396 0.3048)
			(end 0.120396 0.2794)
			(stroke
				(width 0.1)
				(type default)
			)
			(layer "F.Fab")
		)
		(fp_line
			(start 0.120396 0.2794)
			(end -0.12065 0.2794)
			(stroke
				(width 0.1)
				(type default)
			)
			(layer "F.Fab")
		)
		(fp_line
			(start -0.12065 0.3048)
			(end -0.67945 0.3048)
			(stroke
				(width 0.1)
				(type default)
			)
			(layer "F.Fab")
		)
		(fp_line
			(start -0.12065 0.2794)
			(end -0.12065 0.3048)
			(stroke
				(width 0.1)
				(type default)
			)
			(layer "F.Fab")
		)
		(fp_line
			(start -0.12065 -0.2794)
			(end 0.12065 -0.2794)
			(stroke
				(width 0.1)
				(type default)
			)
			(layer "F.Fab")
		)
		(fp_line
			(start -0.12065 -0.305054)
			(end -0.12065 -0.2794)
			(stroke
				(width 0.1)
				(type default)
			)
			(layer "F.Fab")
		)
		(fp_line
			(start -0.67945 0.3048)
			(end -0.67945 -0.305054)
			(stroke
				(width 0.1)
				(type default)
			)
			(layer "F.Fab")
		)
		(fp_line
			(start -0.67945 -0.305054)
			(end -0.12065 -0.305054)
			(stroke
				(width 0.1)
				(type default)
			)
			(layer "F.Fab")
		)
		(pad "1" smd circle
			(at -0.40005 0 180)
			(size 0 0)
			(layers "F.Cu" "F.Mask" "F.Paste")
			(net "PCA9548_PCIE0_ADDR0")
		)
		(pad "2" smd circle
			(at 0.40005 0 180)
			(size 0 0)
			(layers "F.Cu" "F.Mask" "F.Paste")
			(net "GND")
		)
	)
)
